(kicad_pcb
	(version 20260206)
	(generator "pcbnew")
	(generator_version "10.0")
	(general
		(thickness 1.6)
		(legacy_teardrops no)
	)
	(paper "A4")
	(title_block
		(title "04192023_DAF0TMB3IC0_F0TG_MB_C_brd_V02_OCP.brd")
		(comment 1 "Grand Teton / footprint 2783 of 8354 (U26), pads 2334-2448 of 6102")
	)
	(layers
		(0 "F.Cu" signal "TOP")
		(4 "In1.Cu" signal "GND")
		(6 "In2.Cu" signal "IN1")
		(8 "In3.Cu" signal "GND1")
		(10 "In4.Cu" signal "IN2")
		(12 "In5.Cu" signal "GND2")
		(14 "In6.Cu" signal "IN3")
		(16 "In7.Cu" signal "GND3")
		(18 "In8.Cu" signal "VCC")
		(20 "In9.Cu" signal "VCC1")
		(22 "In10.Cu" signal "GND4")
		(24 "In11.Cu" signal "IN4")
		(26 "In12.Cu" signal "GND5")
		(28 "In13.Cu" signal "IN5")
		(30 "In14.Cu" signal "GND6")
		(32 "In15.Cu" signal "IN6")
		(34 "In16.Cu" signal "GND7")
		(2 "B.Cu" signal "BOTTOM")
		(9 "F.Adhes" user "F.Adhesive")
		(11 "B.Adhes" user "B.Adhesive")
		(13 "F.Paste" user "Package Geometry/Pastemask Top")
		(15 "B.Paste" user "Package Geometry/Pastemask Bottom")
		(5 "F.SilkS" user "Ref Des/Silkscreen Top")
		(7 "B.SilkS" user "Ref Des/Silkscreen Bottom")
		(1 "F.Mask" user "Board Geometry/Soldermask Top")
		(3 "B.Mask" user "Board Geometry/Soldermask Bottom")
		(17 "Dwgs.User" user "User.Drawings")
		(19 "Cmts.User" user "User.Comments")
		(21 "Eco1.User" user "User.Eco1")
		(23 "Eco2.User" user "User.Eco2")
		(25 "Edge.Cuts" user "Board Geometry/Outline")
		(27 "Margin" user)
		(31 "F.CrtYd" user "Package Geometry/Place Bound Top")
		(29 "B.CrtYd" user "Package Geometry/Place Bound Bottom")
		(35 "F.Fab" user "Ref Des/Assembly Top")
		(33 "B.Fab" user "Ref Des/Assembly Bottom")
	)
	(footprint ""
		(layer "F.Cu")
		(at 111.927894 -258.880356 180)
		(property "Reference" "U26"
			(at -45.05579 -61.794136 0)
			(unlocked yes)
			(layer "F.SilkS")
			(effects
				(font
					(size 0.7874 0.5842)
					(thickness 0.1524)
				)
			)
		)
		(property "Value" ""
			(at 0 0 180)
			(layer "F.Fab")
			(effects
				(font
					(size 1.27 1.27)
				)
			)
		)
		(duplicate_pad_numbers_are_jumpers no)
		(pad "BR30" smd circle
			(at -7.199884 9.269984 180)
			(size 0.450088 0.450088)
			(layers "F.Cu" "F.Mask" "F.Paste")
			(net "GND")
		)
		(pad "BR31" smd circle
			(at -6.260084 9.269984 180)
			(size 0.450088 0.450088)
			(layers "F.Cu" "F.Mask" "F.Paste")
			(net "PVDDCR_CPU1_P1")
		)
		(pad "BR32" smd circle
			(at -5.32003 9.269984 180)
			(size 0.450088 0.450088)
			(layers "F.Cu" "F.Mask" "F.Paste")
			(net "GND")
		)
		(pad "BR33" smd circle
			(at -4.379976 9.269984 180)
			(size 0.450088 0.450088)
			(layers "F.Cu" "F.Mask" "F.Paste")
			(net "PVDDCR_CPU1_P1")
		)
		(pad "BR34" smd circle
			(at -3.439922 9.269984 180)
			(size 0.450088 0.450088)
			(layers "F.Cu" "F.Mask" "F.Paste")
			(net "GND")
		)
		(pad "BR35" smd circle
			(at -2.500122 9.269984 180)
			(size 0.450088 0.450088)
			(layers "F.Cu" "F.Mask" "F.Paste")
			(net "PVDDCR_CPU1_P1")
		)
		(pad "BR36" smd circle
			(at -1.560068 9.269984 180)
			(size 0.450088 0.450088)
			(layers "F.Cu" "F.Mask" "F.Paste")
			(net "GND")
		)
		(pad "BR40" smd circle
			(at 1.260094 9.269984 180)
			(size 0.450088 0.450088)
			(layers "F.Cu" "F.Mask" "F.Paste")
			(net "PVDDCR_CPU1_P1")
		)
		(pad "BR41" smd circle
			(at 2.199894 9.269984 180)
			(size 0.450088 0.450088)
			(layers "F.Cu" "F.Mask" "F.Paste")
			(net "GND")
		)
		(pad "BR42" smd circle
			(at 3.139948 9.269984 180)
			(size 0.450088 0.450088)
			(layers "F.Cu" "F.Mask" "F.Paste")
			(net "PVDDCR_CPU1_P1")
		)
		(pad "BR43" smd circle
			(at 4.080002 9.269984 180)
			(size 0.450088 0.450088)
			(layers "F.Cu" "F.Mask" "F.Paste")
			(net "GND")
		)
		(pad "BR44" smd circle
			(at 5.020056 9.269984 180)
			(size 0.450088 0.450088)
			(layers "F.Cu" "F.Mask" "F.Paste")
			(net "PVDDCR_CPU1_P1")
		)
		(pad "BR45" smd circle
			(at 5.96011 9.269984 180)
			(size 0.450088 0.450088)
			(layers "F.Cu" "F.Mask" "F.Paste")
			(net "GND")
		)
		(pad "BR46" smd circle
			(at 6.89991 9.269984 180)
			(size 0.450088 0.450088)
			(layers "F.Cu" "F.Mask" "F.Paste")
			(net "PVDDCR_CPU1_P1")
		)
		(pad "BR47" smd circle
			(at 7.839964 9.269984 180)
			(size 0.450088 0.450088)
			(layers "F.Cu" "F.Mask" "F.Paste")
			(net "GND")
		)
		(pad "BR48" smd circle
			(at 8.780018 9.269984 180)
			(size 0.450088 0.450088)
			(layers "F.Cu" "F.Mask" "F.Paste")
			(net "PVDDCR_CPU1_P1")
		)
		(pad "BR49" smd circle
			(at 9.720072 9.269984 180)
			(size 0.450088 0.450088)
			(layers "F.Cu" "F.Mask" "F.Paste")
			(net "GND")
		)
		(pad "BR50" smd circle
			(at 10.659872 9.269984 180)
			(size 0.450088 0.450088)
			(layers "F.Cu" "F.Mask" "F.Paste")
			(net "PVDDCR_CPU1_P1")
		)
		(pad "BR51" smd circle
			(at 11.599926 9.269984 180)
			(size 0.450088 0.450088)
			(layers "F.Cu" "F.Mask" "F.Paste")
			(net "GND")
		)
		(pad "BR52" smd circle
			(at 12.53998 9.269984 180)
			(size 0.450088 0.450088)
			(layers "F.Cu" "F.Mask" "F.Paste")
			(net "PVDDCR_CPU1_P1")
		)
		(pad "BR53" smd circle
			(at 13.480034 9.269984 180)
			(size 0.450088 0.450088)
			(layers "F.Cu" "F.Mask" "F.Paste")
			(net "VSENSE_PVDDIO_P1_DP")
		)
		(pad "BR54" smd circle
			(at 14.420088 9.269984 180)
			(size 0.450088 0.450088)
			(layers "F.Cu" "F.Mask" "F.Paste")
			(net "VSENSE_VSS_SENSE_B_P1")
		)
		(pad "BR55" smd circle
			(at 15.359888 9.269984 180)
			(size 0.450088 0.450088)
			(layers "F.Cu" "F.Mask" "F.Paste")
			(net "GND")
		)
		(pad "BR56" smd circle
			(at 16.299942 9.269984 180)
			(size 0.450088 0.450088)
			(layers "F.Cu" "F.Mask" "F.Paste")
			(net "GND")
		)
		(pad "BR57" smd circle
			(at 17.239996 9.269984 180)
			(size 0.450088 0.450088)
			(layers "F.Cu" "F.Mask" "F.Paste")
			(net "Net_2013")
		)
		(pad "BR58" smd circle
			(at 18.18005 9.269984 180)
			(size 0.450088 0.450088)
			(layers "F.Cu" "F.Mask" "F.Paste")
			(net "PVDDIO_P1")
		)
		(pad "BR59" smd circle
			(at 19.120104 9.269984 180)
			(size 0.450088 0.450088)
			(layers "F.Cu" "F.Mask" "F.Paste")
			(net "GND")
		)
		(pad "BR60" smd circle
			(at 20.059904 9.269984 180)
			(size 0.450088 0.450088)
			(layers "F.Cu" "F.Mask" "F.Paste")
			(net "Net_2021")
		)
		(pad "BR61" smd circle
			(at 20.999958 9.269984 180)
			(size 0.450088 0.450088)
			(layers "F.Cu" "F.Mask" "F.Paste")
			(net "GND")
		)
		(pad "BR62" smd circle
			(at 21.940012 9.269984 180)
			(size 0.450088 0.450088)
			(layers "F.Cu" "F.Mask" "F.Paste")
			(net "GND")
		)
		(pad "BR63" smd circle
			(at 22.880066 9.269984 180)
			(size 0.450088 0.450088)
			(layers "F.Cu" "F.Mask" "F.Paste")
			(net "GND")
		)
		(pad "BR64" smd circle
			(at 23.82012 9.269984 180)
			(size 0.450088 0.450088)
			(layers "F.Cu" "F.Mask" "F.Paste")
			(net "Net_2005")
		)
		(pad "BR65" smd circle
			(at 24.75992 9.269984 180)
			(size 0.450088 0.450088)
			(layers "F.Cu" "F.Mask" "F.Paste")
			(net "PVDDIO_P1")
		)
		(pad "BR66" smd circle
			(at 25.699974 9.269984 180)
			(size 0.450088 0.450088)
			(layers "F.Cu" "F.Mask" "F.Paste")
			(net "GND")
		)
		(pad "BR67" smd circle
			(at 26.640028 9.269984 180)
			(size 0.450088 0.450088)
			(layers "F.Cu" "F.Mask" "F.Paste")
			(net "Net_2037")
		)
		(pad "BR68" smd circle
			(at 27.580082 9.269984 180)
			(size 0.450088 0.450088)
			(layers "F.Cu" "F.Mask" "F.Paste")
			(net "GND")
		)
		(pad "BR69" smd circle
			(at 28.519882 9.269984 180)
			(size 0.450088 0.450088)
			(layers "F.Cu" "F.Mask" "F.Paste")
			(net "GND")
		)
		(pad "BR70" smd circle
			(at 29.459936 9.269984 180)
			(size 0.450088 0.450088)
			(layers "F.Cu" "F.Mask" "F.Paste")
			(net "GND")
		)
		(pad "BR71" smd circle
			(at 30.39999 9.269984 180)
			(size 0.450088 0.450088)
			(layers "F.Cu" "F.Mask" "F.Paste")
			(net "Net_2029")
		)
		(pad "BR72" smd circle
			(at 31.340044 9.269984 180)
			(size 0.450088 0.450088)
			(layers "F.Cu" "F.Mask" "F.Paste")
			(net "PVDDIO_P1")
		)
		(pad "BR73" smd circle
			(at 32.280098 9.269984 180)
			(size 0.450088 0.450088)
			(layers "F.Cu" "F.Mask" "F.Paste")
			(net "GND")
		)
		(pad "BR74" smd circle
			(at 33.219898 9.269984 180)
			(size 0.450088 0.450088)
			(layers "F.Cu" "F.Mask" "F.Paste")
			(net "Net_1997")
		)
		(pad "BR75" smd circle
			(at 34.159952 9.269984 180)
			(size 0.450088 0.450088)
			(layers "F.Cu" "F.Mask" "F.Paste")
			(net "GND")
		)
		(pad "BT2" smd circle
			(at -33.990026 10.07999 180)
			(size 0.450088 0.450088)
			(layers "F.Cu" "F.Mask" "F.Paste")
			(net "M_G_CPU1_SB_CB<4>")
		)
		(pad "BT3" smd circle
			(at -33.049972 10.07999 180)
			(size 0.450088 0.450088)
			(layers "F.Cu" "F.Mask" "F.Paste")
			(net "GND")
		)
		(pad "BT4" smd circle
			(at -32.109918 10.07999 180)
			(size 0.450088 0.450088)
			(layers "F.Cu" "F.Mask" "F.Paste")
			(net "GND")
		)
		(pad "BT5" smd circle
			(at -31.170118 10.07999 180)
			(size 0.450088 0.450088)
			(layers "F.Cu" "F.Mask" "F.Paste")
			(net "GND")
		)
		(pad "BT6" smd circle
			(at -30.230064 10.07999 180)
			(size 0.450088 0.450088)
			(layers "F.Cu" "F.Mask" "F.Paste")
			(net "M_K_CPU1_SB_CB<4>")
		)
		(pad "BT7" smd circle
			(at -29.29001 10.07999 180)
			(size 0.450088 0.450088)
			(layers "F.Cu" "F.Mask" "F.Paste")
			(net "GND")
		)
		(pad "BT8" smd circle
			(at -28.349956 10.07999 180)
			(size 0.450088 0.450088)
			(layers "F.Cu" "F.Mask" "F.Paste")
			(net "GND")
		)
		(pad "BT9" smd circle
			(at -27.409902 10.07999 180)
			(size 0.450088 0.450088)
			(layers "F.Cu" "F.Mask" "F.Paste")
			(net "M_L_CPU1_SB_CB<4>")
		)
		(pad "BT10" smd circle
			(at -26.470102 10.07999 180)
			(size 0.450088 0.450088)
			(layers "F.Cu" "F.Mask" "F.Paste")
			(net "GND")
		)
		(pad "BT11" smd circle
			(at -25.530048 10.07999 180)
			(size 0.450088 0.450088)
			(layers "F.Cu" "F.Mask" "F.Paste")
			(net "GND")
		)
		(pad "BT12" smd circle
			(at -24.589994 10.07999 180)
			(size 0.450088 0.450088)
			(layers "F.Cu" "F.Mask" "F.Paste")
			(net "GND")
		)
		(pad "BT13" smd circle
			(at -23.64994 10.07999 180)
			(size 0.450088 0.450088)
			(layers "F.Cu" "F.Mask" "F.Paste")
			(net "M_H_CPU1_SB_CB<4>")
		)
		(pad "BT14" smd circle
			(at -22.709886 10.07999 180)
			(size 0.450088 0.450088)
			(layers "F.Cu" "F.Mask" "F.Paste")
			(net "GND")
		)
		(pad "BT15" smd circle
			(at -21.770086 10.07999 180)
			(size 0.450088 0.450088)
			(layers "F.Cu" "F.Mask" "F.Paste")
			(net "GND")
		)
		(pad "BT16" smd circle
			(at -20.830032 10.07999 180)
			(size 0.450088 0.450088)
			(layers "F.Cu" "F.Mask" "F.Paste")
			(net "M_J_CPU1_SB_CB<4>")
		)
		(pad "BT17" smd circle
			(at -19.889978 10.07999 180)
			(size 0.450088 0.450088)
			(layers "F.Cu" "F.Mask" "F.Paste")
			(net "GND")
		)
		(pad "BT18" smd circle
			(at -18.949924 10.07999 180)
			(size 0.450088 0.450088)
			(layers "F.Cu" "F.Mask" "F.Paste")
			(net "GND")
		)
		(pad "BT19" smd circle
			(at -18.010124 10.07999 180)
			(size 0.450088 0.450088)
			(layers "F.Cu" "F.Mask" "F.Paste")
			(net "GND")
		)
		(pad "BT20" smd circle
			(at -17.07007 10.07999 180)
			(size 0.450088 0.450088)
			(layers "F.Cu" "F.Mask" "F.Paste")
			(net "M_I_CPU1_SB_CB<4>")
		)
		(pad "BT21" smd circle
			(at -16.130016 10.07999 180)
			(size 0.450088 0.450088)
			(layers "F.Cu" "F.Mask" "F.Paste")
			(net "GND")
		)
		(pad "BT22" smd circle
			(at -15.189962 10.07999 180)
			(size 0.450088 0.450088)
			(layers "F.Cu" "F.Mask" "F.Paste")
			(net "GND")
		)
		(pad "BT23" smd circle
			(at -14.249908 10.07999 180)
			(size 0.450088 0.450088)
			(layers "F.Cu" "F.Mask" "F.Paste")
			(net "PVDDCR_CPU1_P1")
		)
		(pad "BT24" smd circle
			(at -13.310108 10.07999 180)
			(size 0.450088 0.450088)
			(layers "F.Cu" "F.Mask" "F.Paste")
			(net "PVDDCR_CPU1_P1")
		)
		(pad "BT25" smd circle
			(at -12.370054 10.07999 180)
			(size 0.450088 0.450088)
			(layers "F.Cu" "F.Mask" "F.Paste")
			(net "GND")
		)
		(pad "BT26" smd circle
			(at -11.43 10.07999 180)
			(size 0.450088 0.450088)
			(layers "F.Cu" "F.Mask" "F.Paste")
			(net "PVDDCR_CPU1_P1")
		)
		(pad "BT27" smd circle
			(at -10.489946 10.07999 180)
			(size 0.450088 0.450088)
			(layers "F.Cu" "F.Mask" "F.Paste")
			(net "PVDDCR_CPU1_P1")
		)
		(pad "BT28" smd circle
			(at -9.549892 10.07999 180)
			(size 0.450088 0.450088)
			(layers "F.Cu" "F.Mask" "F.Paste")
			(net "GND")
		)
		(pad "BT29" smd circle
			(at -8.610092 10.07999 180)
			(size 0.450088 0.450088)
			(layers "F.Cu" "F.Mask" "F.Paste")
			(net "PVDDCR_CPU1_P1")
		)
		(pad "BT30" smd circle
			(at -7.670038 10.07999 180)
			(size 0.450088 0.450088)
			(layers "F.Cu" "F.Mask" "F.Paste")
			(net "PVDDCR_CPU1_P1")
		)
		(pad "BT31" smd circle
			(at -6.729984 10.07999 180)
			(size 0.450088 0.450088)
			(layers "F.Cu" "F.Mask" "F.Paste")
			(net "GND")
		)
		(pad "BT32" smd circle
			(at -5.78993 10.07999 180)
			(size 0.450088 0.450088)
			(layers "F.Cu" "F.Mask" "F.Paste")
			(net "PVDDCR_CPU1_P1")
		)
		(pad "BT33" smd circle
			(at -4.849876 10.07999 180)
			(size 0.450088 0.450088)
			(layers "F.Cu" "F.Mask" "F.Paste")
			(net "PVDDCR_CPU1_P1")
		)
		(pad "BT34" smd circle
			(at -3.910076 10.07999 180)
			(size 0.450088 0.450088)
			(layers "F.Cu" "F.Mask" "F.Paste")
			(net "GND")
		)
		(pad "BT35" smd circle
			(at -2.970022 10.07999 180)
			(size 0.450088 0.450088)
			(layers "F.Cu" "F.Mask" "F.Paste")
			(net "P5E_CPU1_P2_TX_DN<0>")
		)
		(pad "BT36" smd circle
			(at -2.029968 10.07999 180)
			(size 0.450088 0.450088)
			(layers "F.Cu" "F.Mask" "F.Paste")
			(net "P5E_CPU1_P2_TX_DP<0>")
		)
		(pad "BT37" smd circle
			(at -1.089914 10.07999 180)
			(size 0.450088 0.450088)
			(layers "F.Cu" "F.Mask" "F.Paste")
			(net "GND")
		)
		(pad "BT39" smd circle
			(at 0.78994 10.07999 180)
			(size 0.450088 0.450088)
			(layers "F.Cu" "F.Mask" "F.Paste")
			(net "GND")
		)
		(pad "BT40" smd circle
			(at 1.729994 10.07999 180)
			(size 0.450088 0.450088)
			(layers "F.Cu" "F.Mask" "F.Paste")
			(net "P5E_CPU1_P0_RX_DP<15>")
		)
		(pad "BT41" smd circle
			(at 2.670048 10.07999 180)
			(size 0.450088 0.450088)
			(layers "F.Cu" "F.Mask" "F.Paste")
			(net "P5E_CPU1_P0_RX_DN<15>")
		)
		(pad "BT42" smd circle
			(at 3.610102 10.07999 180)
			(size 0.450088 0.450088)
			(layers "F.Cu" "F.Mask" "F.Paste")
			(net "GND")
		)
		(pad "BT43" smd circle
			(at 4.549902 10.07999 180)
			(size 0.450088 0.450088)
			(layers "F.Cu" "F.Mask" "F.Paste")
			(net "PVDDCR_CPU1_P1")
		)
		(pad "BT44" smd circle
			(at 5.489956 10.07999 180)
			(size 0.450088 0.450088)
			(layers "F.Cu" "F.Mask" "F.Paste")
			(net "PVDDCR_CPU1_P1")
		)
		(pad "BT45" smd circle
			(at 6.43001 10.07999 180)
			(size 0.450088 0.450088)
			(layers "F.Cu" "F.Mask" "F.Paste")
			(net "GND")
		)
		(pad "BT46" smd circle
			(at 7.370064 10.07999 180)
			(size 0.450088 0.450088)
			(layers "F.Cu" "F.Mask" "F.Paste")
			(net "PVDDCR_CPU1_P1")
		)
		(pad "BT47" smd circle
			(at 8.310118 10.07999 180)
			(size 0.450088 0.450088)
			(layers "F.Cu" "F.Mask" "F.Paste")
			(net "PVDDCR_CPU1_P1")
		)
		(pad "BT48" smd circle
			(at 9.249918 10.07999 180)
			(size 0.450088 0.450088)
			(layers "F.Cu" "F.Mask" "F.Paste")
			(net "GND")
		)
		(pad "BT49" smd circle
			(at 10.189972 10.07999 180)
			(size 0.450088 0.450088)
			(layers "F.Cu" "F.Mask" "F.Paste")
			(net "PVDDCR_CPU1_P1")
		)
		(pad "BT50" smd circle
			(at 11.130026 10.07999 180)
			(size 0.450088 0.450088)
			(layers "F.Cu" "F.Mask" "F.Paste")
			(net "PVDDCR_CPU1_P1")
		)
		(pad "BT51" smd circle
			(at 12.07008 10.07999 180)
			(size 0.450088 0.450088)
			(layers "F.Cu" "F.Mask" "F.Paste")
			(net "GND")
		)
		(pad "BT52" smd circle
			(at 13.00988 10.07999 180)
			(size 0.450088 0.450088)
			(layers "F.Cu" "F.Mask" "F.Paste")
			(net "PVDDCR_CPU1_P1")
		)
		(pad "BT53" smd circle
			(at 13.949934 10.07999 180)
			(size 0.450088 0.450088)
			(layers "F.Cu" "F.Mask" "F.Paste")
			(net "PVDDCR_CPU1_P1")
		)
		(pad "BT54" smd circle
			(at 14.889988 10.07999 180)
			(size 0.450088 0.450088)
			(layers "F.Cu" "F.Mask" "F.Paste")
			(net "GND")
		)
		(pad "BT55" smd circle
			(at 15.830042 10.07999 180)
			(size 0.450088 0.450088)
			(layers "F.Cu" "F.Mask" "F.Paste")
			(net "GND")
		)
		(pad "BT56" smd circle
			(at 16.770096 10.07999 180)
			(size 0.450088 0.450088)
			(layers "F.Cu" "F.Mask" "F.Paste")
			(net "M_C_CPU1_SB_CB<4>")
		)
		(pad "BT57" smd circle
			(at 17.709896 10.07999 180)
			(size 0.450088 0.450088)
			(layers "F.Cu" "F.Mask" "F.Paste")
			(net "GND")
		)
		(pad "BT58" smd circle
			(at 18.64995 10.07999 180)
			(size 0.450088 0.450088)
			(layers "F.Cu" "F.Mask" "F.Paste")
			(net "GND")
		)
		(pad "BT59" smd circle
			(at 19.590004 10.07999 180)
			(size 0.450088 0.450088)
			(layers "F.Cu" "F.Mask" "F.Paste")
			(net "GND")
		)
		(pad "BT60" smd circle
			(at 20.530058 10.07999 180)
			(size 0.450088 0.450088)
			(layers "F.Cu" "F.Mask" "F.Paste")
			(net "M_D_CPU1_SB_CB<4>")
		)
		(pad "BT61" smd circle
			(at 21.470112 10.07999 180)
			(size 0.450088 0.450088)
			(layers "F.Cu" "F.Mask" "F.Paste")
			(net "GND")
		)
		(pad "BT62" smd circle
			(at 22.409912 10.07999 180)
			(size 0.450088 0.450088)
			(layers "F.Cu" "F.Mask" "F.Paste")
			(net "GND")
		)
		(pad "BT63" smd circle
			(at 23.349966 10.07999 180)
			(size 0.450088 0.450088)
			(layers "F.Cu" "F.Mask" "F.Paste")
			(net "M_B_CPU1_SB_CB<4>")
		)
		(pad "BT64" smd circle
			(at 24.29002 10.07999 180)
			(size 0.450088 0.450088)
			(layers "F.Cu" "F.Mask" "F.Paste")
			(net "GND")
		)
		(pad "BT65" smd circle
			(at 25.230074 10.07999 180)
			(size 0.450088 0.450088)
			(layers "F.Cu" "F.Mask" "F.Paste")
			(net "GND")
		)
		(pad "BT66" smd circle
			(at 26.170128 10.07999 180)
			(size 0.450088 0.450088)
			(layers "F.Cu" "F.Mask" "F.Paste")
			(net "GND")
		)
		(pad "BT67" smd circle
			(at 27.109928 10.07999 180)
			(size 0.450088 0.450088)
			(layers "F.Cu" "F.Mask" "F.Paste")
			(net "M_F_CPU1_SB_CB<4>")
		)
		(pad "BT68" smd circle
			(at 28.049982 10.07999 180)
			(size 0.450088 0.450088)
			(layers "F.Cu" "F.Mask" "F.Paste")
			(net "GND")
		)
		(pad "BT69" smd circle
			(at 28.990036 10.07999 180)
			(size 0.450088 0.450088)
			(layers "F.Cu" "F.Mask" "F.Paste")
			(net "GND")
		)
		(pad "BT70" smd circle
			(at 29.93009 10.07999 180)
			(size 0.450088 0.450088)
			(layers "F.Cu" "F.Mask" "F.Paste")
			(net "M_E_CPU1_SB_CB<4>")
		)
		(pad "BT71" smd circle
			(at 30.86989 10.07999 180)
			(size 0.450088 0.450088)
			(layers "F.Cu" "F.Mask" "F.Paste")
			(net "GND")
		)
		(pad "BT72" smd circle
			(at 31.809944 10.07999 180)
			(size 0.450088 0.450088)
			(layers "F.Cu" "F.Mask" "F.Paste")
			(net "GND")
		)
		(pad "BT73" smd circle
			(at 32.749998 10.07999 180)
			(size 0.450088 0.450088)
			(layers "F.Cu" "F.Mask" "F.Paste")
			(net "GND")
		)
		(pad "BT74" smd circle
			(at 33.690052 10.07999 180)
			(size 0.450088 0.450088)
			(layers "F.Cu" "F.Mask" "F.Paste")
			(net "M_A_CPU1_SB_CB<4>")
		)
	)
)
